(kicad_pcb
	(version 20260206)
	(generator "pcbnew")
	(generator_version "10.0")
	(general
		(thickness 1.6)
		(legacy_teardrops no)
	)
	(paper "A4")
	(title_block
		(title "Wiwynn_Tioga_Pass_MB.brd")
		(comment 1 "Tioga Pass / footprints 2594-2601 of 4770")
	)
	(layers
		(0 "F.Cu" signal "TOP")
		(4 "In1.Cu" signal "L2GND")
		(6 "In2.Cu" signal "L3")
		(8 "In3.Cu" signal "L4GND")
		(10 "In4.Cu" signal "L5")
		(12 "In5.Cu" signal "L6GND")
		(14 "In6.Cu" signal "L7VCC")
		(16 "In7.Cu" signal "L8VCC")
		(18 "In8.Cu" signal "L9GND")
		(20 "In9.Cu" signal "L10")
		(22 "In10.Cu" signal "L11GND")
		(24 "In11.Cu" signal "L12")
		(26 "In12.Cu" signal "L13GND")
		(2 "B.Cu" signal "BOTTOM")
		(9 "F.Adhes" user "F.Adhesive")
		(11 "B.Adhes" user "B.Adhesive")
		(13 "F.Paste" user "Package Geometry/Pastemask Top")
		(15 "B.Paste" user "Package Geometry/Pastemask Bottom")
		(5 "F.SilkS" user "Ref Des/Silkscreen Top")
		(7 "B.SilkS" user "Ref Des/Silkscreen Bottom")
		(1 "F.Mask" user "Board Geometry/Soldermask Top")
		(3 "B.Mask" user "Board Geometry/Soldermask Bottom")
		(17 "Dwgs.User" user "User.Drawings")
		(19 "Cmts.User" user "User.Comments")
		(21 "Eco1.User" user "User.Eco1")
		(23 "Eco2.User" user "User.Eco2")
		(25 "Edge.Cuts" user "Board Geometry/Outline")
		(27 "Margin" user)
		(31 "F.CrtYd" user "Package Geometry/Place Bound Top")
		(29 "B.CrtYd" user "Package Geometry/Place Bound Bottom")
		(35 "F.Fab" user "Ref Des/Assembly Top")
		(33 "B.Fab" user "Ref Des/Assembly Bottom")
	)
	(footprint ""
		(layer "B.Cu")
		(at 18.6309 -124.5616 180)
		(property "Reference" "C9M3"
			(at 3.03657 4.9784 270)
			(unlocked yes)
			(layer "B.SilkS")
			(effects
				(font
					(size 0.7874 0.5842)
					(thickness 0.1524)
				)
				(justify mirror)
			)
		)
		(property "Value" ""
			(at 0 0 0)
			(layer "B.Fab")
			(effects
				(font
					(size 1.27 1.27)
				)
				(justify mirror)
			)
		)
		(duplicate_pad_numbers_are_jumpers no)
		(fp_line
			(start 2.563114 1.633728)
			(end 1.6002 1.633728)
			(stroke
				(width 0.1524)
				(type default)
			)
			(layer "B.SilkS")
		)
		(fp_line
			(start 2.563114 -1.616456)
			(end 2.563114 1.633728)
			(stroke
				(width 0.1524)
				(type default)
			)
			(layer "B.SilkS")
		)
		(fp_line
			(start 2.286 7.366)
			(end 2.286 1.632712)
			(stroke
				(width 0.1524)
				(type default)
			)
			(layer "B.SilkS")
		)
		(fp_line
			(start 2.286 7.366)
			(end 1.60147 7.366)
			(stroke
				(width 0.1524)
				(type default)
			)
			(layer "B.SilkS")
		)
		(fp_line
			(start 1.6002 -1.616456)
			(end 2.563114 -1.616456)
			(stroke
				(width 0.1524)
				(type default)
			)
			(layer "B.SilkS")
		)
		(fp_line
			(start -1.6002 -1.616456)
			(end -2.504948 -1.616456)
			(stroke
				(width 0.1524)
				(type default)
			)
			(layer "B.SilkS")
		)
		(fp_line
			(start -2.286 7.366)
			(end -1.600708 7.366)
			(stroke
				(width 0.1524)
				(type default)
			)
			(layer "B.SilkS")
		)
		(fp_line
			(start -2.286 7.366)
			(end -2.286 1.63195)
			(stroke
				(width 0.1524)
				(type default)
			)
			(layer "B.SilkS")
		)
		(fp_line
			(start -2.504948 1.633728)
			(end -1.6002 1.633728)
			(stroke
				(width 0.1524)
				(type default)
			)
			(layer "B.SilkS")
		)
		(fp_line
			(start -2.504948 -1.616456)
			(end -2.504948 1.633728)
			(stroke
				(width 0.1524)
				(type default)
			)
			(layer "B.SilkS")
		)
		(fp_rect
			(start 2.286 7.366)
			(end -2.286 -0.254)
			(stroke
				(width 0)
				(type default)
			)
			(fill no)
			(layer "B.CrtYd")
		)
		(fp_line
			(start 2.286 7.366)
			(end 2.286 -0.254)
			(stroke
				(width 0.1)
				(type default)
			)
			(layer "B.Fab")
		)
		(fp_line
			(start 2.286 -0.254)
			(end -2.286 -0.254)
			(stroke
				(width 0.1)
				(type default)
			)
			(layer "B.Fab")
		)
		(fp_line
			(start -2.286 7.366)
			(end 2.286 7.366)
			(stroke
				(width 0.1)
				(type default)
			)
			(layer "B.Fab")
		)
		(fp_line
			(start -2.286 -0.254)
			(end -2.286 7.366)
			(stroke
				(width 0.1)
				(type default)
			)
			(layer "B.Fab")
		)
		(pad "1" smd rect
			(at 0 0)
			(size 2.54 3.048)
			(layers "B.Cu" "B.Mask" "B.Paste")
			(net "P12V_STBY")
		)
		(pad "2" smd rect
			(at 0 7.112)
			(size 2.54 3.048)
			(layers "B.Cu" "B.Mask" "B.Paste")
			(net "GND")
		)
	)
	(footprint ""
		(layer "B.Cu")
		(at 410.591 -48.768)
		(property "Reference" "R1T5"
			(at 0 0 0)
			(layer "B.SilkS")
			(hide yes)
			(effects
				(font
					(size 1.27 1.27)
				)
				(justify mirror)
			)
		)
		(property "Value" ""
			(at 0 0 0)
			(layer "B.Fab")
			(effects
				(font
					(size 1.27 1.27)
				)
				(justify mirror)
			)
		)
		(duplicate_pad_numbers_are_jumpers no)
		(fp_poly
			(pts
				(xy 0.2794 -0.1016) (xy -0.2794 -0.1016) (xy -0.2794 0.9906) (xy 0.2794 0.9906)
			)
			(stroke
				(width 0)
				(type default)
			)
			(fill no)
			(layer "B.CrtYd")
		)
		(fp_line
			(start -0.2794 -0.1016)
			(end 0.2794 -0.1016)
			(stroke
				(width 0.1)
				(type default)
			)
			(layer "B.Fab")
		)
		(fp_line
			(start -0.2794 0.9906)
			(end -0.2794 -0.1016)
			(stroke
				(width 0.1)
				(type default)
			)
			(layer "B.Fab")
		)
		(fp_line
			(start 0.2794 -0.1016)
			(end 0.2794 0.9906)
			(stroke
				(width 0.1)
				(type default)
			)
			(layer "B.Fab")
		)
		(fp_line
			(start 0.2794 0.9906)
			(end -0.2794 0.9906)
			(stroke
				(width 0.1)
				(type default)
			)
			(layer "B.Fab")
		)
		(pad "1" smd rect
			(at 0 0 180)
			(size 0.508 0.508)
			(layers "B.Cu" "B.Mask" "B.Paste")
			(net "P3V3_STBY")
		)
		(pad "2" smd rect
			(at 0 0.889 180)
			(size 0.508 0.508)
			(layers "B.Cu" "B.Mask" "B.Paste")
			(net "FM_BOARD_REV_ID2")
		)
	)
	(footprint ""
		(layer "B.Cu")
		(at 155.194 1.7018 90)
		(property "Reference" "C7U5"
			(at 0 0 90)
			(layer "B.SilkS")
			(hide yes)
			(effects
				(font
					(size 1.27 1.27)
				)
				(justify mirror)
			)
		)
		(property "Value" ""
			(at 0 0 90)
			(layer "B.Fab")
			(effects
				(font
					(size 1.27 1.27)
				)
				(justify mirror)
			)
		)
		(duplicate_pad_numbers_are_jumpers no)
		(fp_poly
			(pts
				(xy 0.4953 -0.2032) (xy -0.4953 -0.2032) (xy -0.4953 1.6002) (xy 0.4953 1.6002)
			)
			(stroke
				(width 0)
				(type default)
			)
			(fill no)
			(layer "B.CrtYd")
		)
		(fp_line
			(start 0.4953 -0.2032)
			(end -0.4953 -0.2032)
			(stroke
				(width 0.1)
				(type default)
			)
			(layer "B.Fab")
		)
		(fp_line
			(start -0.4953 -0.2032)
			(end -0.4953 1.6002)
			(stroke
				(width 0.1)
				(type default)
			)
			(layer "B.Fab")
		)
		(fp_line
			(start 0.4953 1.6002)
			(end 0.4953 -0.2032)
			(stroke
				(width 0.1)
				(type default)
			)
			(layer "B.Fab")
		)
		(fp_line
			(start -0.4953 1.6002)
			(end 0.4953 1.6002)
			(stroke
				(width 0.1)
				(type default)
			)
			(layer "B.Fab")
		)
		(pad "1" smd rect
			(at 0 0 270)
			(size 0.762 0.889)
			(layers "B.Cu" "B.Mask" "B.Paste")
			(net "PVPP_GHJ")
		)
		(pad "2" smd rect
			(at 0 1.397 270)
			(size 0.762 0.889)
			(layers "B.Cu" "B.Mask" "B.Paste")
			(net "GND")
		)
		(zone
			(layer "B.Cu")
			(hatch none 0.5)
			(connect_pads
				(clearance 0)
			)
			(min_thickness 0.25)
			(keepout
				(tracks not_allowed)
				(vias allowed)
				(pads allowed)
				(copperpour not_allowed)
				(footprints allowed)
			)
			(placement
				(enabled no)
				(sheetname "")
			)
			(fill
				(thermal_gap 0.5)
				(thermal_bridge_width 0.5)
				(island_removal_mode 0)
			)
			(polygon
				(pts
					(xy 155.6385 1.3208) (xy 155.6385 2.0828) (xy 156.1465 2.0828) (xy 156.1465 1.3208)
				)
			)
		)
	)
	(footprint ""
		(layer "B.Cu")
		(at 266.397232 -12.954 90)
		(property "Reference" "C5G46"
			(at -1.14681 0.76708 180)
			(unlocked yes)
			(layer "B.SilkS")
			(effects
				(font
					(size 0.7874 0.5842)
					(thickness 0.1524)
				)
				(justify mirror)
			)
		)
		(property "Value" ""
			(at 0 0 90)
			(layer "B.Fab")
			(effects
				(font
					(size 1.27 1.27)
				)
				(justify mirror)
			)
		)
		(duplicate_pad_numbers_are_jumpers no)
		(fp_rect
			(start -0.4953 -0.2032)
			(end 0.4953 1.6002)
			(stroke
				(width 0)
				(type default)
			)
			(fill no)
			(layer "B.CrtYd")
		)
		(fp_line
			(start 0.4953 -0.2032)
			(end -0.4953 -0.2032)
			(stroke
				(width 0.1)
				(type default)
			)
			(layer "B.Fab")
		)
		(fp_line
			(start -0.4953 -0.2032)
			(end -0.4953 1.6002)
			(stroke
				(width 0.1)
				(type default)
			)
			(layer "B.Fab")
		)
		(fp_line
			(start 0.4953 1.6002)
			(end 0.4953 -0.2032)
			(stroke
				(width 0.1)
				(type default)
			)
			(layer "B.Fab")
		)
		(fp_line
			(start -0.4953 1.6002)
			(end 0.4953 1.6002)
			(stroke
				(width 0.1)
				(type default)
			)
			(layer "B.Fab")
		)
		(pad "1" smd rect
			(at 0 0 270)
			(size 0.762 0.889)
			(layers "B.Cu" "B.Mask" "B.Paste")
			(net "PVDDQ_ABC")
		)
		(pad "2" smd rect
			(at 0 1.397 270)
			(size 0.762 0.889)
			(layers "B.Cu" "B.Mask" "B.Paste")
			(net "GND")
		)
		(zone
			(layer "B.Cu")
			(hatch none 0.5)
			(connect_pads
				(clearance 0)
			)
			(min_thickness 0.25)
			(keepout
				(tracks not_allowed)
				(vias allowed)
				(pads allowed)
				(copperpour not_allowed)
				(footprints allowed)
			)
			(placement
				(enabled no)
				(sheetname "")
			)
			(fill
				(thermal_gap 0.5)
				(thermal_bridge_width 0.5)
				(island_removal_mode 0)
			)
			(polygon
				(pts
					(xy 266.841732 -12.573) (xy 267.349732 -12.573) (xy 267.349732 -13.335) (xy 266.841732 -13.335)
				)
			)
		)
	)
	(footprint ""
		(layer "B.Cu")
		(at 16.383 -90.805)
		(property "Reference" "C9W2"
			(at 0 0 0)
			(layer "B.SilkS")
			(hide yes)
			(effects
				(font
					(size 1.27 1.27)
				)
				(justify mirror)
			)
		)
		(property "Value" "*"
			(at -1.1811 -2.8194 0)
			(unlocked yes)
			(layer "B.Fab")
			(hide yes)
			(effects
				(font
					(size 1.27 1.016)
					(thickness 0.1524)
				)
				(justify mirror)
			)
		)
		(property "Device Type" "SC22P50V2JN-4GP_SMD-BCG-SC22P5A"
			(at -1.1811 -4.3434 0)
			(unlocked yes)
			(layer "B.Fab")
			(hide yes)
			(effects
				(font
					(size 1.27 1.016)
					(thickness 0.1524)
				)
				(justify mirror)
			)
		)
		(duplicate_pad_numbers_are_jumpers no)
		(fp_rect
			(start 0.4318 0.9525)
			(end -0.4318 -0.9525)
			(stroke
				(width 0)
				(type default)
			)
			(fill no)
			(layer "B.CrtYd")
		)
		(fp_rect
			(start 0.4318 0.9525)
			(end -0.4318 -0.9525)
			(stroke
				(width 0)
				(type default)
			)
			(fill no)
			(layer "B.Fab")
		)
		(pad "1" smd custom
			(at 0 -0.4445 180)
			(size 0.1524 0.1524)
			(layers "B.Cu" "B.Mask" "B.Paste")
			(net "A_P12V_STBY_ADR_TRIGGER")
			(options
				(clearance outline)
				(anchor circle)
			)
			(primitives
				(gr_poly
					(pts
						(arc
							(start 0.3048 0.2032)
							(mid 0.275042 0.275042)
							(end 0.2032 0.3048)
						)
						(arc
							(start -0.2032 0.3048)
							(mid -0.275042 0.275042)
							(end -0.3048 0.2032)
						)
						(arc
							(start -0.3048 -0.2032)
							(mid -0.275042 -0.275042)
							(end -0.2032 -0.3048)
						)
						(arc
							(start 0.2032 -0.3048)
							(mid 0.275042 -0.275042)
							(end 0.3048 -0.2032)
						)
					)
					(width 0)
					(fill yes)
				)
			)
		)
		(pad "2" smd custom
			(at 0 0.4445 180)
			(size 0.1524 0.1524)
			(layers "B.Cu" "B.Mask" "B.Paste")
			(net "AGND_HSC")
			(options
				(clearance outline)
				(anchor circle)
			)
			(primitives
				(gr_poly
					(pts
						(arc
							(start 0.3048 0.2032)
							(mid 0.275042 0.275042)
							(end 0.2032 0.3048)
						)
						(arc
							(start -0.2032 0.3048)
							(mid -0.275042 0.275042)
							(end -0.3048 0.2032)
						)
						(arc
							(start -0.3048 -0.2032)
							(mid -0.275042 -0.275042)
							(end -0.2032 -0.3048)
						)
						(arc
							(start 0.2032 -0.3048)
							(mid 0.275042 -0.275042)
							(end 0.3048 -0.2032)
						)
					)
					(width 0)
					(fill yes)
				)
			)
		)
	)
	(footprint ""
		(layer "B.Cu")
		(at 471.95486 -130.0734)
		(property "Reference" "R1M21"
			(at 0 0 0)
			(layer "B.SilkS")
			(hide yes)
			(effects
				(font
					(size 1.27 1.27)
				)
				(justify mirror)
			)
		)
		(property "Value" ""
			(at 0 0 0)
			(layer "B.Fab")
			(effects
				(font
					(size 1.27 1.27)
				)
				(justify mirror)
			)
		)
		(duplicate_pad_numbers_are_jumpers no)
		(fp_poly
			(pts
				(xy 0.2794 -0.1016) (xy -0.2794 -0.1016) (xy -0.2794 0.9906) (xy 0.2794 0.9906)
			)
			(stroke
				(width 0)
				(type default)
			)
			(fill no)
			(layer "B.CrtYd")
		)
		(fp_line
			(start -0.2794 -0.1016)
			(end 0.2794 -0.1016)
			(stroke
				(width 0.1)
				(type default)
			)
			(layer "B.Fab")
		)
		(fp_line
			(start -0.2794 0.9906)
			(end -0.2794 -0.1016)
			(stroke
				(width 0.1)
				(type default)
			)
			(layer "B.Fab")
		)
		(fp_line
			(start 0.2794 -0.1016)
			(end 0.2794 0.9906)
			(stroke
				(width 0.1)
				(type default)
			)
			(layer "B.Fab")
		)
		(fp_line
			(start 0.2794 0.9906)
			(end -0.2794 0.9906)
			(stroke
				(width 0.1)
				(type default)
			)
			(layer "B.Fab")
		)
		(pad "1" smd rect
			(at 0 0 180)
			(size 0.508 0.508)
			(layers "B.Cu" "B.Mask" "B.Paste")
			(net "P1V8_MCP_CPU0")
		)
		(pad "2" smd rect
			(at 0 0.889 180)
			(size 0.508 0.508)
			(layers "B.Cu" "B.Mask" "B.Paste")
			(net "JTAG_MCP_TRST_N")
		)
		(zone
			(layer "B.Cu")
			(hatch none 0.5)
			(connect_pads
				(clearance 0)
			)
			(min_thickness 0.25)
			(keepout
				(tracks allowed)
				(vias not_allowed)
				(pads allowed)
				(copperpour not_allowed)
				(footprints allowed)
			)
			(placement
				(enabled no)
				(sheetname "")
			)
			(fill
				(thermal_gap 0.5)
				(thermal_bridge_width 0.5)
				(island_removal_mode 0)
			)
			(polygon
				(pts
					(xy 472.20886 -129.8194) (xy 471.70086 -129.8194) (xy 471.70086 -129.4384) (xy 472.20886 -129.4384)
				)
			)
		)
		(zone
			(layer "B.Cu")
			(hatch none 0.5)
			(connect_pads
				(clearance 0)
			)
			(min_thickness 0.25)
			(keepout
				(tracks not_allowed)
				(vias allowed)
				(pads allowed)
				(copperpour not_allowed)
				(footprints allowed)
			)
			(placement
				(enabled no)
				(sheetname "")
			)
			(fill
				(thermal_gap 0.5)
				(thermal_bridge_width 0.5)
				(island_removal_mode 0)
			)
			(polygon
				(pts
					(xy 472.20886 -129.4384) (xy 471.70086 -129.4384) (xy 471.70086 -129.8194) (xy 472.20886 -129.8194)
				)
			)
		)
	)
	(footprint ""
		(layer "B.Cu")
		(at 391.573512 -43.599608 180)
		(property "Reference" "Q7E3"
			(at -2.65938 -1.15697 0)
			(unlocked yes)
			(layer "B.SilkS")
			(effects
				(font
					(size 0.7874 0.5842)
					(thickness 0.1524)
				)
				(justify left mirror)
			)
		)
		(property "Value" ""
			(at 0 0 0)
			(layer "B.Fab")
			(effects
				(font
					(size 1.27 1.27)
				)
				(justify mirror)
			)
		)
		(duplicate_pad_numbers_are_jumpers no)
		(fp_circle
			(center 0.508 -0.7874)
			(end 0.381 -0.7874)
			(stroke
				(width 0.254)
				(type default)
			)
			(fill no)
			(layer "B.SilkS")
		)
		(fp_poly
			(pts
				(xy -0.2159 1.7526) (xy -1.5621 1.7526) (xy -1.5621 -0.4572) (xy -0.2159 -0.4572)
			)
			(stroke
				(width 0)
				(type default)
			)
			(fill no)
			(layer "B.CrtYd")
		)
		(fp_line
			(start -0.2159 1.75514)
			(end -1.5621 1.75514)
			(stroke
				(width 0.1)
				(type default)
			)
			(layer "B.Fab")
		)
		(fp_line
			(start -0.2159 -0.45466)
			(end -0.2159 1.75514)
			(stroke
				(width 0.1)
				(type default)
			)
			(layer "B.Fab")
		)
		(fp_line
			(start -1.5621 1.75514)
			(end -1.5621 -0.45466)
			(stroke
				(width 0.1)
				(type default)
			)
			(layer "B.Fab")
		)
		(fp_line
			(start -1.5621 -0.45466)
			(end -0.2159 -0.45466)
			(stroke
				(width 0.1)
				(type default)
			)
			(layer "B.Fab")
		)
		(fp_circle
			(center 0.508 -0.7874)
			(end 0.381 -0.7874)
			(stroke
				(width 0.254)
				(type default)
			)
			(fill no)
			(layer "B.Fab")
		)
		(pad "1" smd rect
			(at 0 0)
			(size 1.016 0.381)
			(layers "B.Cu" "B.Mask" "B.Paste")
			(net "GND")
		)
		(pad "2" smd rect
			(at 0 0.65024)
			(size 1.016 0.381)
			(layers "B.Cu" "B.Mask" "B.Paste")
			(net "FM_SYS_THROTTLE_LVC3")
		)
		(pad "3" smd rect
			(at 0 1.30048)
			(size 1.016 0.381)
			(layers "B.Cu" "B.Mask" "B.Paste")
			(net "H_CPU1_PROCHOT_G_N")
		)
		(pad "4" smd rect
			(at -1.778 1.30048)
			(size 1.016 0.381)
			(layers "B.Cu" "B.Mask" "B.Paste")
			(net "GND")
		)
		(pad "5" smd rect
			(at -1.778 0.65024)
			(size 1.016 0.381)
			(layers "B.Cu" "B.Mask" "B.Paste")
			(net "FM_SYS_THROTTLE_LVC3")
		)
		(pad "6" smd rect
			(at -1.778 0)
			(size 1.016 0.381)
			(layers "B.Cu" "B.Mask" "B.Paste")
			(net "H_CPU0_PROCHOT_G_N")
		)
		(zone
			(layer "B.Cu")
			(hatch none 0.5)
			(connect_pads
				(clearance 0)
			)
			(min_thickness 0.25)
			(keepout
				(tracks allowed)
				(vias not_allowed)
				(pads allowed)
				(copperpour not_allowed)
				(footprints allowed)
			)
			(placement
				(enabled no)
				(sheetname "")
			)
			(fill
				(thermal_gap 0.5)
				(thermal_bridge_width 0.5)
				(island_removal_mode 0)
			)
			(polygon
				(pts
					(xy 391.065512 -43.409108) (xy 392.081512 -43.409108) (xy 392.081512 -45.098208) (xy 391.065512 -45.098208)
				)
			)
		)
		(zone
			(layer "B.Cu")
			(hatch none 0.5)
			(connect_pads
				(clearance 0)
			)
			(min_thickness 0.25)
			(keepout
				(tracks allowed)
				(vias not_allowed)
				(pads allowed)
				(copperpour not_allowed)
				(footprints allowed)
			)
			(placement
				(enabled no)
				(sheetname "")
			)
			(fill
				(thermal_gap 0.5)
				(thermal_bridge_width 0.5)
				(island_removal_mode 0)
			)
			(polygon
				(pts
					(xy 392.843512 -43.409108) (xy 393.859512 -43.409108) (xy 393.859512 -45.098208) (xy 392.843512 -45.098208)
				)
			)
		)
	)
	(footprint ""
		(layer "B.Cu")
		(at 367.284 -62.2935 180)
		(property "Reference" "R3P43"
			(at 0 0 0)
			(layer "B.SilkS")
			(hide yes)
			(effects
				(font
					(size 1.27 1.27)
				)
				(justify mirror)
			)
		)
		(property "Value" ""
			(at 0 0 0)
			(layer "B.Fab")
			(effects
				(font
					(size 1.27 1.27)
				)
				(justify mirror)
			)
		)
		(duplicate_pad_numbers_are_jumpers no)
		(fp_poly
			(pts
				(xy 0.2794 -0.1016) (xy -0.2794 -0.1016) (xy -0.2794 0.9906) (xy 0.2794 0.9906)
			)
			(stroke
				(width 0)
				(type default)
			)
			(fill no)
			(layer "B.CrtYd")
		)
		(fp_line
			(start 0.2794 0.9906)
			(end -0.2794 0.9906)
			(stroke
				(width 0.1)
				(type default)
			)
			(layer "B.Fab")
		)
		(fp_line
			(start 0.2794 -0.1016)
			(end 0.2794 0.9906)
			(stroke
				(width 0.1)
				(type default)
			)
			(layer "B.Fab")
		)
		(fp_line
			(start -0.2794 0.9906)
			(end -0.2794 -0.1016)
			(stroke
				(width 0.1)
				(type default)
			)
			(layer "B.Fab")
		)
		(fp_line
			(start -0.2794 -0.1016)
			(end 0.2794 -0.1016)
			(stroke
				(width 0.1)
				(type default)
			)
			(layer "B.Fab")
		)
		(pad "1" smd rect
			(at 0 0)
			(size 0.508 0.508)
			(layers "B.Cu" "B.Mask" "B.Paste")
			(net "FM_CPU_CATERR_LVT3_R2_N")
		)
		(pad "2" smd rect
			(at 0 0.889)
			(size 0.508 0.508)
			(layers "B.Cu" "B.Mask" "B.Paste")
			(net "FM_CPU_CATERR_LVT3_N")
		)
		(zone
			(layer "B.Cu")
			(hatch none 0.5)
			(connect_pads
				(clearance 0)
			)
			(min_thickness 0.25)
			(keepout
				(tracks not_allowed)
				(vias allowed)
				(pads allowed)
				(copperpour not_allowed)
				(footprints allowed)
			)
			(placement
				(enabled no)
				(sheetname "")
			)
			(fill
				(thermal_gap 0.5)
				(thermal_bridge_width 0.5)
				(island_removal_mode 0)
			)
			(polygon
				(pts
					(xy 367.03 -62.9285) (xy 367.538 -62.9285) (xy 367.538 -62.5475) (xy 367.03 -62.5475)
				)
			)
		)
		(zone
			(layer "B.Cu")
			(hatch none 0.5)
			(connect_pads
				(clearance 0)
			)
			(min_thickness 0.25)
			(keepout
				(tracks allowed)
				(vias not_allowed)
				(pads allowed)
				(copperpour not_allowed)
				(footprints allowed)
			)
			(placement
				(enabled no)
				(sheetname "")
			)
			(fill
				(thermal_gap 0.5)
				(thermal_bridge_width 0.5)
				(island_removal_mode 0)
			)
			(polygon
				(pts
					(xy 367.03 -62.5475) (xy 367.538 -62.5475) (xy 367.538 -62.9285) (xy 367.03 -62.9285)
				)
			)
		)
	)
)
